# T6G (Grand Teton) — schematic netlist excerpt (pin names and nets, part order shuffled) for the footprints in the layout excerpt that follows; sources: Cadence DE-HDL packaged netlist, KiCad conversion of 04192023_DAF0TMB3IC0_F0TG_MB_C_brd_V02_OCP.brd

R912  Q_RES  4.7K 5% EMPTY  pkg 0201LF  page 353 : A = P1V8_CPU1_RT_1D ; B = JTAG_TEST_MODE_RT_CPU1_P3
L2  Q_INDUCTOR  FCM2012KF-601T/0.5A IND  pkg SMLF  page 183 : \1\ = P3V3_AUX ; \2\ = P3V3_9ZXL045_P1_VDD
C2157  Q_CAP  22UF 4V 20% X6S  pkg C0402  page 68 : A = PVDDCR_SOC_P0 ; B = GND
C1829  Q_CAP  22UF 16V 20% X6S  pkg C0805  page 137 : A = P12V_OCP_V3_2_R ; B = GND

(kicad_pcb
	(version 20260206)
	(generator "pcbnew")
	(generator_version "10.0")
	(general
		(thickness 1.6)
		(legacy_teardrops no)
	)
	(paper "A4")
	(title_block
		(title "04192023_DAF0TMB3IC0_F0TG_MB_C_brd_V02_OCP.brd")
		(comment 1 "Grand Teton / footprints 4392-4395 of 8354")
	)
	(layers
		(0 "F.Cu" signal "TOP")
		(4 "In1.Cu" signal "GND")
		(6 "In2.Cu" signal "IN1")
		(8 "In3.Cu" signal "GND1")
		(10 "In4.Cu" signal "IN2")
		(12 "In5.Cu" signal "GND2")
		(14 "In6.Cu" signal "IN3")
		(16 "In7.Cu" signal "GND3")
		(18 "In8.Cu" signal "VCC")
		(20 "In9.Cu" signal "VCC1")
		(22 "In10.Cu" signal "GND4")
		(24 "In11.Cu" signal "IN4")
		(26 "In12.Cu" signal "GND5")
		(28 "In13.Cu" signal "IN5")
		(30 "In14.Cu" signal "GND6")
		(32 "In15.Cu" signal "IN6")
		(34 "In16.Cu" signal "GND7")
		(2 "B.Cu" signal "BOTTOM")
		(9 "F.Adhes" user "F.Adhesive")
		(11 "B.Adhes" user "B.Adhesive")
		(13 "F.Paste" user "Package Geometry/Pastemask Top")
		(15 "B.Paste" user "Package Geometry/Pastemask Bottom")
		(5 "F.SilkS" user "Ref Des/Silkscreen Top")
		(7 "B.SilkS" user "Ref Des/Silkscreen Bottom")
		(1 "F.Mask" user "Board Geometry/Soldermask Top")
		(3 "B.Mask" user "Board Geometry/Soldermask Bottom")
		(17 "Dwgs.User" user "User.Drawings")
		(19 "Cmts.User" user "User.Comments")
		(21 "Eco1.User" user "User.Eco1")
		(23 "Eco2.User" user "User.Eco2")
		(25 "Edge.Cuts" user "Board Geometry/Outline")
		(27 "Margin" user)
		(31 "F.CrtYd" user "Package Geometry/Place Bound Top")
		(29 "B.CrtYd" user "Package Geometry/Place Bound Bottom")
		(35 "F.Fab" user "Ref Des/Assembly Top")
		(33 "B.Fab" user "Ref Des/Assembly Bottom")
	)
	(footprint ""
		(layer "F.Cu")
		(at 100.442522 -410.672788)
		(property "Reference" "L2"
			(at 0 0 0)
			(layer "F.SilkS")
			(hide yes)
			(effects
				(font
					(size 1.27 1.27)
				)
			)
		)
		(property "Value" ""
			(at 0 0 0)
			(layer "F.Fab")
			(effects
				(font
					(size 1.27 1.27)
				)
			)
		)
		(duplicate_pad_numbers_are_jumpers no)
		(fp_line
			(start -1.63576 -0.8128)
			(end -1.63576 0.8128)
			(stroke
				(width 0.1524)
				(type default)
			)
			(layer "F.SilkS")
		)
		(fp_line
			(start -1.63576 -0.8128)
			(end 1.63576 -0.8128)
			(stroke
				(width 0.1524)
				(type default)
			)
			(layer "F.SilkS")
		)
		(fp_line
			(start 1.63576 -0.8128)
			(end 1.63576 0.8128)
			(stroke
				(width 0.1524)
				(type default)
			)
			(layer "F.SilkS")
		)
		(fp_line
			(start 1.63576 0.8128)
			(end -1.63576 0.8128)
			(stroke
				(width 0.1524)
				(type default)
			)
			(layer "F.SilkS")
		)
		(fp_line
			(start -1.56083 -0.738632)
			(end -1.56083 0.7366)
			(stroke
				(width 0.1)
				(type default)
			)
			(layer "F.Fab")
		)
		(fp_line
			(start -1.56083 0.7366)
			(end -1.524 0.7366)
			(stroke
				(width 0.1)
				(type default)
			)
			(layer "F.Fab")
		)
		(fp_line
			(start -1.524 0.7366)
			(end 1.524 0.7366)
			(stroke
				(width 0.1)
				(type default)
			)
			(layer "F.Fab")
		)
		(fp_line
			(start 1.524 0.7366)
			(end 1.560576 0.7366)
			(stroke
				(width 0.1)
				(type default)
			)
			(layer "F.Fab")
		)
		(fp_line
			(start 1.560576 -0.738632)
			(end -1.56083 -0.738632)
			(stroke
				(width 0.1)
				(type default)
			)
			(layer "F.Fab")
		)
		(fp_line
			(start 1.560576 0.7366)
			(end 1.560576 -0.738632)
			(stroke
				(width 0.1)
				(type default)
			)
			(layer "F.Fab")
		)
		(pad "1" smd rect
			(at -0.94996 0 180)
			(size 1.1176 1.3716)
			(layers "F.Cu" "F.Mask" "F.Paste")
			(net "P3V3_AUX")
		)
		(pad "2" smd rect
			(at 0.94996 0 180)
			(size 1.1176 1.3716)
			(layers "F.Cu" "F.Mask" "F.Paste")
			(net "P3V3_9ZXL045_P1_VDD")
		)
	)
	(footprint ""
		(layer "F.Cu")
		(at 365.835692 -259.355082 180)
		(property "Reference" "C2157"
			(at 0 0 180)
			(layer "F.SilkS")
			(hide yes)
			(effects
				(font
					(size 1.27 1.27)
				)
			)
		)
		(property "Value" ""
			(at 0 0 180)
			(layer "F.Fab")
			(effects
				(font
					(size 1.27 1.27)
				)
			)
		)
		(duplicate_pad_numbers_are_jumpers no)
		(fp_line
			(start 0.7874 0.4064)
			(end -0.7874 0.4064)
			(stroke
				(width 0.1524)
				(type default)
			)
			(layer "F.SilkS")
		)
		(fp_line
			(start 0.7874 -0.4064)
			(end 0.7874 0.4064)
			(stroke
				(width 0.1524)
				(type default)
			)
			(layer "F.SilkS")
		)
		(fp_line
			(start -0.7874 0.4064)
			(end -0.7874 -0.4064)
			(stroke
				(width 0.1524)
				(type default)
			)
			(layer "F.SilkS")
		)
		(fp_line
			(start -0.7874 -0.4064)
			(end 0.7874 -0.4064)
			(stroke
				(width 0.1524)
				(type default)
			)
			(layer "F.SilkS")
		)
		(fp_line
			(start 0.67945 0.3048)
			(end 0.120396 0.3048)
			(stroke
				(width 0.1)
				(type default)
			)
			(layer "F.Fab")
		)
		(fp_line
			(start 0.67945 -0.3048)
			(end 0.67945 0.3048)
			(stroke
				(width 0.1)
				(type default)
			)
			(layer "F.Fab")
		)
		(fp_line
			(start 0.12065 -0.2794)
			(end 0.12065 -0.3048)
			(stroke
				(width 0.1)
				(type default)
			)
			(layer "F.Fab")
		)
		(fp_line
			(start 0.12065 -0.3048)
			(end 0.67945 -0.3048)
			(stroke
				(width 0.1)
				(type default)
			)
			(layer "F.Fab")
		)
		(fp_line
			(start 0.120396 0.3048)
			(end 0.120396 0.2794)
			(stroke
				(width 0.1)
				(type default)
			)
			(layer "F.Fab")
		)
		(fp_line
			(start 0.120396 0.2794)
			(end -0.12065 0.2794)
			(stroke
				(width 0.1)
				(type default)
			)
			(layer "F.Fab")
		)
		(fp_line
			(start -0.12065 0.3048)
			(end -0.67945 0.3048)
			(stroke
				(width 0.1)
				(type default)
			)
			(layer "F.Fab")
		)
		(fp_line
			(start -0.12065 0.2794)
			(end -0.12065 0.3048)
			(stroke
				(width 0.1)
				(type default)
			)
			(layer "F.Fab")
		)
		(fp_line
			(start -0.12065 -0.2794)
			(end 0.12065 -0.2794)
			(stroke
				(width 0.1)
				(type default)
			)
			(layer "F.Fab")
		)
		(fp_line
			(start -0.12065 -0.305054)
			(end -0.12065 -0.2794)
			(stroke
				(width 0.1)
				(type default)
			)
			(layer "F.Fab")
		)
		(fp_line
			(start -0.67945 0.3048)
			(end -0.67945 -0.305054)
			(stroke
				(width 0.1)
				(type default)
			)
			(layer "F.Fab")
		)
		(fp_line
			(start -0.67945 -0.305054)
			(end -0.12065 -0.305054)
			(stroke
				(width 0.1)
				(type default)
			)
			(layer "F.Fab")
		)
		(pad "1" smd circle
			(at -0.40005 0 180)
			(size 0 0)
			(layers "F.Cu" "F.Mask" "F.Paste")
			(net "PVDDCR_SOC_P0")
		)
		(pad "2" smd circle
			(at 0.40005 0 180)
			(size 0 0)
			(layers "F.Cu" "F.Mask" "F.Paste")
			(net "GND")
		)
	)
	(footprint ""
		(layer "F.Cu")
		(at 65.193164 -17.227804 180)
		(property "Reference" "C1829"
			(at 0 0 180)
			(layer "F.SilkS")
			(hide yes)
			(effects
				(font
					(size 1.27 1.27)
				)
			)
		)
		(property "Value" ""
			(at 0 0 180)
			(layer "F.Fab")
			(effects
				(font
					(size 1.27 1.27)
				)
			)
		)
		(duplicate_pad_numbers_are_jumpers no)
		(fp_line
			(start 1.524 0.762)
			(end -1.524 0.762)
			(stroke
				(width 0.1524)
				(type default)
			)
			(layer "F.SilkS")
		)
		(fp_line
			(start 1.524 -0.762)
			(end 1.524 0.762)
			(stroke
				(width 0.1524)
				(type default)
			)
			(layer "F.SilkS")
		)
		(fp_line
			(start -1.524 0.762)
			(end -1.524 -0.762)
			(stroke
				(width 0.1524)
				(type default)
			)
			(layer "F.SilkS")
		)
		(fp_line
			(start -1.524 -0.762)
			(end 1.524 -0.762)
			(stroke
				(width 0.1524)
				(type default)
			)
			(layer "F.SilkS")
		)
		(fp_line
			(start 1.1049 0.724916)
			(end 1.1049 -0.724916)
			(stroke
				(width 0.1)
				(type default)
			)
			(layer "F.Fab")
		)
		(fp_line
			(start 1.1049 -0.724916)
			(end -1.1049 -0.724916)
			(stroke
				(width 0.1)
				(type default)
			)
			(layer "F.Fab")
		)
		(fp_line
			(start -1.1049 0.724916)
			(end 1.1049 0.724916)
			(stroke
				(width 0.1)
				(type default)
			)
			(layer "F.Fab")
		)
		(fp_line
			(start -1.1049 -0.724916)
			(end -1.1049 0.724916)
			(stroke
				(width 0.1)
				(type default)
			)
			(layer "F.Fab")
		)
		(pad "1" smd rect
			(at -0.889 0)
			(size 1.016 1.27)
			(layers "F.Cu" "F.Mask" "F.Paste")
			(net "P12V_OCP_V3_2_R")
		)
		(pad "2" smd rect
			(at 0.889 0)
			(size 1.016 1.27)
			(layers "F.Cu" "F.Mask" "F.Paste")
			(net "GND")
		)
	)
	(footprint ""
		(layer "F.Cu")
		(at 116.158518 -395.340586 -90)
		(property "Reference" "R912"
			(at 0 0 270)
			(layer "F.SilkS")
			(hide yes)
			(effects
				(font
					(size 1.27 1.27)
				)
			)
		)
		(property "Value" ""
			(at 0 0 270)
			(layer "F.Fab")
			(effects
				(font
					(size 1.27 1.27)
				)
			)
		)
		(duplicate_pad_numbers_are_jumpers no)
		(fp_line
			(start -0.32512 0.175006)
			(end -0.32512 -0.175006)
			(stroke
				(width 0.1)
				(type default)
			)
			(layer "F.Fab")
		)
		(fp_line
			(start 0.32512 0.175006)
			(end -0.32512 0.175006)
			(stroke
				(width 0.1)
				(type default)
			)
			(layer "F.Fab")
		)
		(fp_line
			(start -0.32512 -0.175006)
			(end 0.32512 -0.175006)
			(stroke
				(width 0.1)
				(type default)
			)
			(layer "F.Fab")
		)
		(fp_line
			(start 0.32512 -0.175006)
			(end 0.32512 0.175006)
			(stroke
				(width 0.1)
				(type default)
			)
			(layer "F.Fab")
		)
		(pad "1" smd rect
			(at -0.2667 0 270)
			(size 0.3048 0.381)
			(layers "F.Cu" "F.Mask" "F.Paste")
			(net "P1V8_CPU1_RT_1D")
		)
		(pad "2" smd rect
			(at 0.2667 0 90)
			(size 0.3048 0.381)
			(layers "F.Cu" "F.Mask" "F.Paste")
			(net "JTAG_TEST_MODE_RT_CPU1_P3")
		)
	)
)
